# ZAIUS-MB-EVT3-HW-EBOM-X00_20161228-add_2nd_source_X15-20170106-Final.xls — Single-Sole Source Parts List (bom)
| FOXCONN TECHNOLOGY GROUP |  |  |  |  |  |  |  |  |  |  |  |  |  |  |  |  |  |
| BILL OF MATERIAL |  |  |  |  |  |  |  |  |  |  |  |  |  |  |  |  |  |
| REV OF  BOM |  | CUSTOMER | <name> |  | CUSTOMER P/N |  | PWA P/N： | PWA DESCRIPTION |  |  | PRODUCT CODE |  |  | PWA REV |  | DATE |  |
| Sourcing (Single or Sole | Critical Commodity (Y or N) | Component Class (1, 2, Other) | Customer PSL (Y/N) | Item Number | Foxconn P/N | Customer P/N | Part Description | Mfr. 1 | Mfr Part # 1 | Proposed Mfr. 2 | Proposed Mfr. 2 PN | Qty | RoHS Status | Location | 2nd Source Qual Build: | Customer Comments | ODM Comments |
